(kicad_pcb
	(version 20260206)
	(generator "pcbnew")
	(generator_version "10.0")
	(general
		(thickness 1.6)
		(legacy_teardrops no)
	)
	(paper "A4")
	(title_block
		(title "v1-chassis-manager — T6M_CM_d_v01_1031_1645.brd")
		(comment 1 "Open CloudServer (Microsoft) / footprints 1603-1612 of 2512")
	)
	(layers
		(0 "F.Cu" signal "TOP")
		(4 "In1.Cu" signal "GND1")
		(6 "In2.Cu" signal "IN1")
		(8 "In3.Cu" signal "VCC1")
		(10 "In4.Cu" signal "VCC2")
		(12 "In5.Cu" signal "GND2")
		(14 "In6.Cu" signal "IN2")
		(16 "In7.Cu" signal "IN3")
		(18 "In8.Cu" signal "GND3")
		(2 "B.Cu" signal "BOTTOM")
		(9 "F.Adhes" user "F.Adhesive")
		(11 "B.Adhes" user "B.Adhesive")
		(13 "F.Paste" user "Package Geometry/Pastemask Top")
		(15 "B.Paste" user "Package Geometry/Pastemask Bottom")
		(5 "F.SilkS" user "Ref Des/Silkscreen Top")
		(7 "B.SilkS" user "Ref Des/Silkscreen Bottom")
		(1 "F.Mask" user "Board Geometry/Soldermask Top")
		(3 "B.Mask" user "Board Geometry/Soldermask Bottom")
		(17 "Dwgs.User" user "User.Drawings")
		(19 "Cmts.User" user "User.Comments")
		(21 "Eco1.User" user "User.Eco1")
		(23 "Eco2.User" user "User.Eco2")
		(25 "Edge.Cuts" user "Board Geometry/Outline")
		(27 "Margin" user)
		(31 "F.CrtYd" user "Package Geometry/Place Bound Top")
		(29 "B.CrtYd" user "Package Geometry/Place Bound Bottom")
		(35 "F.Fab" user "Ref Des/Assembly Top")
		(33 "B.Fab" user "Ref Des/Assembly Bottom")
	)
	(footprint ""
		(layer "B.Cu")
		(at 58.10123 -67.092322 90)
		(property "Reference" "R1044"
			(at -34.333688 -13.67282 270)
			(unlocked yes)
			(layer "B.SilkS")
			(effects
				(font
					(size 0.7874 0.5842)
					(thickness 0.1524)
				)
				(justify left mirror)
			)
		)
		(property "Value" ""
			(at 0 0 90)
			(layer "B.Fab")
			(effects
				(font
					(size 1.27 1.27)
				)
				(justify mirror)
			)
		)
		(duplicate_pad_numbers_are_jumpers no)
		(fp_line
			(start 0.7874 -0.4064)
			(end -0.7874 -0.4064)
			(stroke
				(width 0.1524)
				(type default)
			)
			(layer "B.SilkS")
		)
		(fp_line
			(start -0.7874 -0.4064)
			(end -0.7874 0.4064)
			(stroke
				(width 0.1524)
				(type default)
			)
			(layer "B.SilkS")
		)
		(fp_line
			(start 0.7874 0.4064)
			(end 0.7874 -0.4064)
			(stroke
				(width 0.1524)
				(type default)
			)
			(layer "B.SilkS")
		)
		(fp_line
			(start -0.7874 0.4064)
			(end 0.7874 0.4064)
			(stroke
				(width 0.1524)
				(type default)
			)
			(layer "B.SilkS")
		)
		(fp_poly
			(pts
				(xy 0.508 0.2794) (xy 0.508 0.2286) (xy 0.635 0.2286) (xy 0.635 -0.254) (xy 0.5334 -0.254) (xy 0.5334 -0.2794)
				(xy -0.5334 -0.2794) (xy -0.5334 -0.254) (xy -0.635 -0.254) (xy -0.635 0.254) (xy -0.5334 0.254)
				(xy -0.5334 0.2794)
			)
			(stroke
				(width 0)
				(type default)
			)
			(fill no)
			(layer "B.CrtYd")
		)
		(pad "1" smd rect
			(at -0.40005 0 270)
			(size 0.4572 0.508)
			(layers "B.Cu" "B.Mask" "B.Paste")
			(net "PWRGD_NODE1_DDR3_SYSPWRGD")
		)
		(pad "2" smd rect
			(at 0.40005 0 270)
			(size 0.4572 0.508)
			(layers "B.Cu" "B.Mask" "B.Paste")
			(net "PV_VDDR_NODE1")
		)
	)
	(footprint ""
		(layer "B.Cu")
		(at 54.469538 -79.531718)
		(property "Reference" "C49"
			(at -12.404598 30.92069 0)
			(unlocked yes)
			(layer "B.SilkS")
			(effects
				(font
					(size 0.7874 0.5842)
					(thickness 0.1524)
				)
				(justify left mirror)
			)
		)
		(property "Value" ""
			(at 0 0 0)
			(layer "B.Fab")
			(effects
				(font
					(size 1.27 1.27)
				)
				(justify mirror)
			)
		)
		(duplicate_pad_numbers_are_jumpers no)
		(fp_line
			(start -0.7874 -0.4064)
			(end -0.7874 0.4064)
			(stroke
				(width 0.1524)
				(type default)
			)
			(layer "B.SilkS")
		)
		(fp_line
			(start -0.7874 0.4064)
			(end 0.7874 0.4064)
			(stroke
				(width 0.1524)
				(type default)
			)
			(layer "B.SilkS")
		)
		(fp_line
			(start 0 0.381)
			(end 0 -0.381)
			(stroke
				(width 0.1524)
				(type default)
			)
			(layer "B.SilkS")
		)
		(fp_line
			(start 0.7874 -0.4064)
			(end -0.7874 -0.4064)
			(stroke
				(width 0.1524)
				(type default)
			)
			(layer "B.SilkS")
		)
		(fp_line
			(start 0.7874 0.4064)
			(end 0.7874 -0.4064)
			(stroke
				(width 0.1524)
				(type default)
			)
			(layer "B.SilkS")
		)
		(fp_poly
			(pts
				(xy 0.5334 0.254) (xy 0.635 0.254) (xy 0.635 0.2286) (xy 0.635 -0.254) (xy 0.5334 -0.254) (xy 0.5334 -0.2794)
				(xy -0.5334 -0.2794) (xy -0.5334 -0.254) (xy -0.635 -0.254) (xy -0.635 0.254) (xy -0.5334 0.254)
				(xy -0.5334 0.2794) (xy 0.508 0.2794) (xy 0.5334 0.2794)
			)
			(stroke
				(width 0)
				(type default)
			)
			(fill no)
			(layer "B.CrtYd")
		)
		(pad "1" smd rect
			(at -0.40005 0 180)
			(size 0.4572 0.508)
			(layers "B.Cu" "B.Mask" "B.Paste")
			(net "P1V05_NODE1")
		)
		(pad "2" smd rect
			(at 0.40005 0 180)
			(size 0.4572 0.508)
			(layers "B.Cu" "B.Mask" "B.Paste")
			(net "GND")
		)
	)
	(footprint ""
		(layer "B.Cu")
		(at 45.625258 -60.445396 -90)
		(property "Reference" "C21"
			(at 2.31775 2.249424 270)
			(unlocked yes)
			(layer "B.SilkS")
			(effects
				(font
					(size 0.7874 0.5842)
					(thickness 0.1524)
				)
				(justify left mirror)
			)
		)
		(property "Value" ""
			(at 0 0 90)
			(layer "B.Fab")
			(effects
				(font
					(size 1.27 1.27)
				)
				(justify mirror)
			)
		)
		(duplicate_pad_numbers_are_jumpers no)
		(fp_line
			(start -0.7874 0.4064)
			(end 0.7874 0.4064)
			(stroke
				(width 0.1524)
				(type default)
			)
			(layer "B.SilkS")
		)
		(fp_line
			(start 0.7874 0.4064)
			(end 0.7874 -0.4064)
			(stroke
				(width 0.1524)
				(type default)
			)
			(layer "B.SilkS")
		)
		(fp_line
			(start 0 0.381)
			(end 0 -0.381)
			(stroke
				(width 0.1524)
				(type default)
			)
			(layer "B.SilkS")
		)
		(fp_line
			(start -0.7874 -0.4064)
			(end -0.7874 0.4064)
			(stroke
				(width 0.1524)
				(type default)
			)
			(layer "B.SilkS")
		)
		(fp_line
			(start 0.7874 -0.4064)
			(end -0.7874 -0.4064)
			(stroke
				(width 0.1524)
				(type default)
			)
			(layer "B.SilkS")
		)
		(fp_poly
			(pts
				(xy 0.5334 0.254) (xy 0.635 0.254) (xy 0.635 0.2286) (xy 0.635 -0.254) (xy 0.5334 -0.254) (xy 0.5334 -0.2794)
				(xy -0.5334 -0.2794) (xy -0.5334 -0.254) (xy -0.635 -0.254) (xy -0.635 0.254) (xy -0.5334 0.254)
				(xy -0.5334 0.2794) (xy 0.508 0.2794) (xy 0.5334 0.2794)
			)
			(stroke
				(width 0)
				(type default)
			)
			(fill no)
			(layer "B.CrtYd")
		)
		(pad "1" smd rect
			(at -0.40005 0 90)
			(size 0.4572 0.508)
			(layers "B.Cu" "B.Mask" "B.Paste")
			(net "P2E_CPU_SATA_NODE1_TX_C_DP")
		)
		(pad "2" smd rect
			(at 0.40005 0 90)
			(size 0.4572 0.508)
			(layers "B.Cu" "B.Mask" "B.Paste")
			(net "P2E_CPU_SATA_NODE1_TX_DP")
		)
	)
	(footprint ""
		(layer "B.Cu")
		(at 134.435088 -46.960536 90)
		(property "Reference" "R1136"
			(at 3.102864 11.385042 270)
			(unlocked yes)
			(layer "B.SilkS")
			(effects
				(font
					(size 0.7874 0.5842)
					(thickness 0.1524)
				)
				(justify left mirror)
			)
		)
		(property "Value" ""
			(at 0 0 90)
			(layer "B.Fab")
			(effects
				(font
					(size 1.27 1.27)
				)
				(justify mirror)
			)
		)
		(duplicate_pad_numbers_are_jumpers no)
		(fp_line
			(start 0.7874 -0.4064)
			(end -0.7874 -0.4064)
			(stroke
				(width 0.1524)
				(type default)
			)
			(layer "B.SilkS")
		)
		(fp_line
			(start -0.7874 -0.4064)
			(end -0.7874 0.4064)
			(stroke
				(width 0.1524)
				(type default)
			)
			(layer "B.SilkS")
		)
		(fp_line
			(start 0.7874 0.4064)
			(end 0.7874 -0.4064)
			(stroke
				(width 0.1524)
				(type default)
			)
			(layer "B.SilkS")
		)
		(fp_line
			(start -0.7874 0.4064)
			(end 0.7874 0.4064)
			(stroke
				(width 0.1524)
				(type default)
			)
			(layer "B.SilkS")
		)
		(fp_poly
			(pts
				(xy 0.508 0.2794) (xy 0.508 0.2286) (xy 0.635 0.2286) (xy 0.635 -0.254) (xy 0.5334 -0.254) (xy 0.5334 -0.2794)
				(xy -0.5334 -0.2794) (xy -0.5334 -0.254) (xy -0.635 -0.254) (xy -0.635 0.254) (xy -0.5334 0.254)
				(xy -0.5334 0.2794)
			)
			(stroke
				(width 0)
				(type default)
			)
			(fill no)
			(layer "B.CrtYd")
		)
		(pad "1" smd rect
			(at -0.40005 0 270)
			(size 0.4572 0.508)
			(layers "B.Cu" "B.Mask" "B.Paste")
			(net "P5V_NODE1")
		)
		(pad "2" smd rect
			(at 0.40005 0 270)
			(size 0.4572 0.508)
			(layers "B.Cu" "B.Mask" "B.Paste")
			(net "UART_RTS_P3_R_N")
		)
	)
	(footprint ""
		(layer "B.Cu")
		(at 121.72061 -38.446456 180)
		(property "Reference" "R1204"
			(at 3.310636 -0.941578 0)
			(unlocked yes)
			(layer "B.SilkS")
			(effects
				(font
					(size 0.7874 0.5842)
					(thickness 0.1524)
				)
				(justify left mirror)
			)
		)
		(property "Value" ""
			(at 0 0 0)
			(layer "B.Fab")
			(effects
				(font
					(size 1.27 1.27)
				)
				(justify mirror)
			)
		)
		(duplicate_pad_numbers_are_jumpers no)
		(fp_line
			(start 0.7874 0.4064)
			(end 0.7874 -0.4064)
			(stroke
				(width 0.1524)
				(type default)
			)
			(layer "B.SilkS")
		)
		(fp_line
			(start 0.7874 -0.4064)
			(end -0.7874 -0.4064)
			(stroke
				(width 0.1524)
				(type default)
			)
			(layer "B.SilkS")
		)
		(fp_line
			(start -0.7874 0.4064)
			(end 0.7874 0.4064)
			(stroke
				(width 0.1524)
				(type default)
			)
			(layer "B.SilkS")
		)
		(fp_line
			(start -0.7874 -0.4064)
			(end -0.7874 0.4064)
			(stroke
				(width 0.1524)
				(type default)
			)
			(layer "B.SilkS")
		)
		(fp_poly
			(pts
				(xy 0.508 0.2794) (xy 0.508 0.2286) (xy 0.635 0.2286) (xy 0.635 -0.254) (xy 0.5334 -0.254) (xy 0.5334 -0.2794)
				(xy -0.5334 -0.2794) (xy -0.5334 -0.254) (xy -0.635 -0.254) (xy -0.635 0.254) (xy -0.5334 0.254)
				(xy -0.5334 0.2794)
			)
			(stroke
				(width 0)
				(type default)
			)
			(fill no)
			(layer "B.CrtYd")
		)
		(pad "1" smd rect
			(at -0.40005 0)
			(size 0.4572 0.508)
			(layers "B.Cu" "B.Mask" "B.Paste")
			(net "SIO_JTAG_CPLD3_TCK_R")
		)
		(pad "2" smd rect
			(at 0.40005 0)
			(size 0.4572 0.508)
			(layers "B.Cu" "B.Mask" "B.Paste")
			(net "P3V3_NODE1")
		)
	)
	(footprint ""
		(layer "B.Cu")
		(at 114.28476 -185.205624 90)
		(property "Reference" "R958"
			(at 3.957828 0.471424 270)
			(unlocked yes)
			(layer "B.SilkS")
			(effects
				(font
					(size 0.7874 0.5842)
					(thickness 0.1524)
				)
				(justify left mirror)
			)
		)
		(property "Value" ""
			(at 0 0 90)
			(layer "B.Fab")
			(effects
				(font
					(size 1.27 1.27)
				)
				(justify mirror)
			)
		)
		(duplicate_pad_numbers_are_jumpers no)
		(fp_line
			(start 0.7874 -0.4064)
			(end -0.7874 -0.4064)
			(stroke
				(width 0.1524)
				(type default)
			)
			(layer "B.SilkS")
		)
		(fp_line
			(start -0.7874 -0.4064)
			(end -0.7874 0.4064)
			(stroke
				(width 0.1524)
				(type default)
			)
			(layer "B.SilkS")
		)
		(fp_line
			(start 0.7874 0.4064)
			(end 0.7874 -0.4064)
			(stroke
				(width 0.1524)
				(type default)
			)
			(layer "B.SilkS")
		)
		(fp_line
			(start -0.7874 0.4064)
			(end 0.7874 0.4064)
			(stroke
				(width 0.1524)
				(type default)
			)
			(layer "B.SilkS")
		)
		(fp_poly
			(pts
				(xy 0.508 0.2794) (xy 0.508 0.2286) (xy 0.635 0.2286) (xy 0.635 -0.254) (xy 0.5334 -0.254) (xy 0.5334 -0.2794)
				(xy -0.5334 -0.2794) (xy -0.5334 -0.254) (xy -0.635 -0.254) (xy -0.635 0.254) (xy -0.5334 0.254)
				(xy -0.5334 0.2794)
			)
			(stroke
				(width 0)
				(type default)
			)
			(fill no)
			(layer "B.CrtYd")
		)
		(pad "1" smd rect
			(at -0.40005 0 270)
			(size 0.4572 0.508)
			(layers "B.Cu" "B.Mask" "B.Paste")
			(net "UART_T7_NODE1_TXD")
		)
		(pad "2" smd rect
			(at 0.40005 0 270)
			(size 0.4572 0.508)
			(layers "B.Cu" "B.Mask" "B.Paste")
			(net "UART_T7_NODE1_TXD_R")
		)
	)
	(footprint ""
		(layer "B.Cu")
		(at 136.50976 -187.872624 -90)
		(property "Reference" "C633"
			(at -4.565396 1.38938 270)
			(unlocked yes)
			(layer "B.SilkS")
			(effects
				(font
					(size 0.7874 0.5842)
					(thickness 0.1524)
				)
				(justify left mirror)
			)
		)
		(property "Value" ""
			(at 0 0 90)
			(layer "B.Fab")
			(effects
				(font
					(size 1.27 1.27)
				)
				(justify mirror)
			)
		)
		(duplicate_pad_numbers_are_jumpers no)
		(fp_line
			(start -0.7874 0.4064)
			(end 0.7874 0.4064)
			(stroke
				(width 0.1524)
				(type default)
			)
			(layer "B.SilkS")
		)
		(fp_line
			(start 0.7874 0.4064)
			(end 0.7874 -0.4064)
			(stroke
				(width 0.1524)
				(type default)
			)
			(layer "B.SilkS")
		)
		(fp_line
			(start 0 0.381)
			(end 0 -0.381)
			(stroke
				(width 0.1524)
				(type default)
			)
			(layer "B.SilkS")
		)
		(fp_line
			(start -0.7874 -0.4064)
			(end -0.7874 0.4064)
			(stroke
				(width 0.1524)
				(type default)
			)
			(layer "B.SilkS")
		)
		(fp_line
			(start 0.7874 -0.4064)
			(end -0.7874 -0.4064)
			(stroke
				(width 0.1524)
				(type default)
			)
			(layer "B.SilkS")
		)
		(fp_poly
			(pts
				(xy 0.5334 0.254) (xy 0.635 0.254) (xy 0.635 0.2286) (xy 0.635 -0.254) (xy 0.5334 -0.254) (xy 0.5334 -0.2794)
				(xy -0.5334 -0.2794) (xy -0.5334 -0.254) (xy -0.635 -0.254) (xy -0.635 0.254) (xy -0.5334 0.254)
				(xy -0.5334 0.2794) (xy 0.508 0.2794) (xy 0.5334 0.2794)
			)
			(stroke
				(width 0)
				(type default)
			)
			(fill no)
			(layer "B.CrtYd")
		)
		(pad "1" smd rect
			(at -0.40005 0 90)
			(size 0.4572 0.508)
			(layers "B.Cu" "B.Mask" "B.Paste")
			(net "T9_NODE4_EN_R")
		)
		(pad "2" smd rect
			(at 0.40005 0 90)
			(size 0.4572 0.508)
			(layers "B.Cu" "B.Mask" "B.Paste")
			(net "GND")
		)
	)
	(footprint ""
		(layer "B.Cu")
		(at 43.671236 -97.104708 -90)
		(property "Reference" "R129"
			(at -1.440688 -0.033274 270)
			(unlocked yes)
			(layer "B.SilkS")
			(effects
				(font
					(size 0.7874 0.5842)
					(thickness 0.1524)
				)
				(justify left mirror)
			)
		)
		(property "Value" ""
			(at 0 0 90)
			(layer "B.Fab")
			(effects
				(font
					(size 1.27 1.27)
				)
				(justify mirror)
			)
		)
		(duplicate_pad_numbers_are_jumpers no)
		(fp_line
			(start -0.7874 0.4064)
			(end 0.7874 0.4064)
			(stroke
				(width 0.1524)
				(type default)
			)
			(layer "B.SilkS")
		)
		(fp_line
			(start 0.7874 0.4064)
			(end 0.7874 -0.4064)
			(stroke
				(width 0.1524)
				(type default)
			)
			(layer "B.SilkS")
		)
		(fp_line
			(start -0.7874 -0.4064)
			(end -0.7874 0.4064)
			(stroke
				(width 0.1524)
				(type default)
			)
			(layer "B.SilkS")
		)
		(fp_line
			(start 0.7874 -0.4064)
			(end -0.7874 -0.4064)
			(stroke
				(width 0.1524)
				(type default)
			)
			(layer "B.SilkS")
		)
		(fp_poly
			(pts
				(xy 0.508 0.2794) (xy 0.508 0.2286) (xy 0.635 0.2286) (xy 0.635 -0.254) (xy 0.5334 -0.254) (xy 0.5334 -0.2794)
				(xy -0.5334 -0.2794) (xy -0.5334 -0.254) (xy -0.635 -0.254) (xy -0.635 0.254) (xy -0.5334 0.254)
				(xy -0.5334 0.2794)
			)
			(stroke
				(width 0)
				(type default)
			)
			(fill no)
			(layer "B.CrtYd")
		)
		(pad "1" smd rect
			(at -0.40005 0 90)
			(size 0.4572 0.508)
			(layers "B.Cu" "B.Mask" "B.Paste")
			(net "P3V3_NODE1")
		)
		(pad "2" smd rect
			(at 0.40005 0 90)
			(size 0.4572 0.508)
			(layers "B.Cu" "B.Mask" "B.Paste")
			(net "SMB_MUX_CPU_ICS_NODE1_DAT")
		)
	)
	(footprint ""
		(layer "B.Cu")
		(at 133.08076 -184.951624 -90)
		(property "Reference" "C725"
			(at -4.357624 1.543812 270)
			(unlocked yes)
			(layer "B.SilkS")
			(effects
				(font
					(size 0.7874 0.5842)
					(thickness 0.1524)
				)
				(justify left mirror)
			)
		)
		(property "Value" ""
			(at 0 0 90)
			(layer "B.Fab")
			(effects
				(font
					(size 1.27 1.27)
				)
				(justify mirror)
			)
		)
		(duplicate_pad_numbers_are_jumpers no)
		(fp_line
			(start -0.7874 0.4064)
			(end 0.7874 0.4064)
			(stroke
				(width 0.1524)
				(type default)
			)
			(layer "B.SilkS")
		)
		(fp_line
			(start 0.7874 0.4064)
			(end 0.7874 -0.4064)
			(stroke
				(width 0.1524)
				(type default)
			)
			(layer "B.SilkS")
		)
		(fp_line
			(start 0 0.381)
			(end 0 -0.381)
			(stroke
				(width 0.1524)
				(type default)
			)
			(layer "B.SilkS")
		)
		(fp_line
			(start -0.7874 -0.4064)
			(end -0.7874 0.4064)
			(stroke
				(width 0.1524)
				(type default)
			)
			(layer "B.SilkS")
		)
		(fp_line
			(start 0.7874 -0.4064)
			(end -0.7874 -0.4064)
			(stroke
				(width 0.1524)
				(type default)
			)
			(layer "B.SilkS")
		)
		(fp_poly
			(pts
				(xy 0.5334 0.254) (xy 0.635 0.254) (xy 0.635 0.2286) (xy 0.635 -0.254) (xy 0.5334 -0.254) (xy 0.5334 -0.2794)
				(xy -0.5334 -0.2794) (xy -0.5334 -0.254) (xy -0.635 -0.254) (xy -0.635 0.254) (xy -0.5334 0.254)
				(xy -0.5334 0.2794) (xy 0.508 0.2794) (xy 0.5334 0.2794)
			)
			(stroke
				(width 0)
				(type default)
			)
			(fill no)
			(layer "B.CrtYd")
		)
		(pad "1" smd rect
			(at -0.40005 0 90)
			(size 0.4572 0.508)
			(layers "B.Cu" "B.Mask" "B.Paste")
			(net "UART_T9_NODE2_RXD")
		)
		(pad "2" smd rect
			(at 0.40005 0 90)
			(size 0.4572 0.508)
			(layers "B.Cu" "B.Mask" "B.Paste")
			(net "GND")
		)
	)
	(footprint ""
		(layer "B.Cu")
		(at 63.553086 -131.661662 90)
		(property "Reference" "C293"
			(at -54.974236 -41.15181 270)
			(unlocked yes)
			(layer "B.SilkS")
			(effects
				(font
					(size 0.7874 0.5842)
					(thickness 0.1524)
				)
				(justify left mirror)
			)
		)
		(property "Value" ""
			(at 0 0 90)
			(layer "B.Fab")
			(effects
				(font
					(size 1.27 1.27)
				)
				(justify mirror)
			)
		)
		(duplicate_pad_numbers_are_jumpers no)
		(fp_line
			(start 0.7874 -0.4064)
			(end -0.7874 -0.4064)
			(stroke
				(width 0.1524)
				(type default)
			)
			(layer "B.SilkS")
		)
		(fp_line
			(start -0.7874 -0.4064)
			(end -0.7874 0.4064)
			(stroke
				(width 0.1524)
				(type default)
			)
			(layer "B.SilkS")
		)
		(fp_line
			(start 0 0.381)
			(end 0 -0.381)
			(stroke
				(width 0.1524)
				(type default)
			)
			(layer "B.SilkS")
		)
		(fp_line
			(start 0.7874 0.4064)
			(end 0.7874 -0.4064)
			(stroke
				(width 0.1524)
				(type default)
			)
			(layer "B.SilkS")
		)
		(fp_line
			(start -0.7874 0.4064)
			(end 0.7874 0.4064)
			(stroke
				(width 0.1524)
				(type default)
			)
			(layer "B.SilkS")
		)
		(fp_poly
			(pts
				(xy 0.5334 0.254) (xy 0.635 0.254) (xy 0.635 0.2286) (xy 0.635 -0.254) (xy 0.5334 -0.254) (xy 0.5334 -0.2794)
				(xy -0.5334 -0.2794) (xy -0.5334 -0.254) (xy -0.635 -0.254) (xy -0.635 0.254) (xy -0.5334 0.254)
				(xy -0.5334 0.2794) (xy 0.508 0.2794) (xy 0.5334 0.2794)
			)
			(stroke
				(width 0)
				(type default)
			)
			(fill no)
			(layer "B.CrtYd")
		)
		(pad "1" smd rect
			(at -0.40005 0 270)
			(size 0.4572 0.508)
			(layers "B.Cu" "B.Mask" "B.Paste")
			(net "P1V26_BMC_NODE1")
		)
		(pad "2" smd rect
			(at 0.40005 0 270)
			(size 0.4572 0.508)
			(layers "B.Cu" "B.Mask" "B.Paste")
			(net "GND")
		)
	)
)
